(kicad_pcb
	(version 20260206)
	(generator "pcbnew")
	(generator_version "10.0")
	(general
		(thickness 1.6)
		(legacy_teardrops no)
	)
	(paper "A4")
	(title_block
		(title "baseboard — 13948-1b.1110WZS1818.brd")
		(comment 1 "Honey Badger (Wiwynn) / footprints 1713-1720 of 2523")
	)
	(layers
		(0 "F.Cu" signal "TOP")
		(4 "In1.Cu" signal "L2GND")
		(6 "In2.Cu" signal "L3")
		(8 "In3.Cu" signal "L4VCC")
		(10 "In4.Cu" signal "L5VCC")
		(12 "In5.Cu" signal "L6")
		(14 "In6.Cu" signal "L7GND")
		(2 "B.Cu" signal "BOTTOM")
		(9 "F.Adhes" user "F.Adhesive")
		(11 "B.Adhes" user "B.Adhesive")
		(13 "F.Paste" user "Package Geometry/Pastemask Top")
		(15 "B.Paste" user "Package Geometry/Pastemask Bottom")
		(5 "F.SilkS" user "Ref Des/Silkscreen Top")
		(7 "B.SilkS" user "Ref Des/Silkscreen Bottom")
		(1 "F.Mask" user "Board Geometry/Soldermask Top")
		(3 "B.Mask" user "Board Geometry/Soldermask Bottom")
		(17 "Dwgs.User" user "User.Drawings")
		(19 "Cmts.User" user "User.Comments")
		(21 "Eco1.User" user "User.Eco1")
		(23 "Eco2.User" user "User.Eco2")
		(25 "Edge.Cuts" user "Board Geometry/Outline")
		(27 "Margin" user)
		(31 "F.CrtYd" user "Package Geometry/Place Bound Top")
		(29 "B.CrtYd" user "Package Geometry/Place Bound Bottom")
		(35 "F.Fab" user "Ref Des/Assembly Top")
		(33 "B.Fab" user "Ref Des/Assembly Bottom")
	)
	(footprint ""
		(layer "F.Cu")
		(at 303.320958 -64.135 -90)
		(property "Reference" "R220"
			(at 0 0 270)
			(layer "F.SilkS")
			(hide yes)
			(effects
				(font
					(size 1.27 1.27)
				)
			)
		)
		(property "Value" "0R2J-2-GP"
			(at 0.064008 -3.993896 270)
			(unlocked yes)
			(layer "F.Fab")
			(hide yes)
			(effects
				(font
					(size 1.016 1.016)
					(thickness 0.1524)
				)
			)
		)
		(property "Device Type" "R402H16"
			(at 0.064008 -5.517896 270)
			(unlocked yes)
			(layer "F.Fab")
			(hide yes)
			(effects
				(font
					(size 1.016 1.016)
					(thickness 0.1524)
				)
			)
		)
		(duplicate_pad_numbers_are_jumpers no)
		(fp_line
			(start -0.508 -0.9398)
			(end -0.508 0.9398)
			(stroke
				(width 0.1524)
				(type default)
			)
			(layer "F.SilkS")
		)
		(fp_line
			(start 0.508 -0.9398)
			(end -0.508 -0.9398)
			(stroke
				(width 0.1524)
				(type default)
			)
			(layer "F.SilkS")
		)
		(fp_rect
			(start -0.508 0.9398)
			(end 0.508 -0.9398)
			(stroke
				(width 0)
				(type default)
			)
			(fill no)
			(layer "F.CrtYd")
		)
		(fp_rect
			(start -0.508 0.9398)
			(end 0.508 -0.9398)
			(stroke
				(width 0)
				(type default)
			)
			(fill no)
			(layer "F.Fab")
		)
		(pad "1" smd custom
			(at 0 -0.4445 270)
			(size 0.1397 0.1397)
			(layers "F.Cu" "F.Mask" "F.Paste")
			(net "NCSI_10G_TXD1_R")
			(options
				(clearance outline)
				(anchor circle)
			)
			(primitives
				(gr_poly
					(pts
						(arc
							(start -0.1778 -0.2794)
							(mid -0.249642 -0.249642)
							(end -0.2794 -0.1778)
						)
						(arc
							(start -0.2794 0.1778)
							(mid -0.249642 0.249642)
							(end -0.1778 0.2794)
						)
						(arc
							(start 0.1778 0.2794)
							(mid 0.249642 0.249642)
							(end 0.2794 0.1778)
						)
						(arc
							(start 0.2794 -0.1778)
							(mid 0.249642 -0.249642)
							(end 0.1778 -0.2794)
						)
					)
					(width 0)
					(fill yes)
				)
			)
		)
		(pad "2" smd custom
			(at 0 0.4445 270)
			(size 0.1397 0.1397)
			(layers "F.Cu" "F.Mask" "F.Paste")
			(net "NCSI_10G_TXD1")
			(options
				(clearance outline)
				(anchor circle)
			)
			(primitives
				(gr_poly
					(pts
						(arc
							(start -0.1778 -0.2794)
							(mid -0.249642 -0.249642)
							(end -0.2794 -0.1778)
						)
						(arc
							(start -0.2794 0.1778)
							(mid -0.249642 0.249642)
							(end -0.1778 0.2794)
						)
						(arc
							(start 0.1778 0.2794)
							(mid 0.249642 0.249642)
							(end 0.2794 0.1778)
						)
						(arc
							(start 0.2794 -0.1778)
							(mid 0.249642 -0.249642)
							(end 0.1778 -0.2794)
						)
					)
					(width 0)
					(fill yes)
				)
			)
		)
	)
	(footprint ""
		(layer "F.Cu")
		(at 42.7482 -114.7572 180)
		(property "Reference" "SR848"
			(at 0 0 180)
			(layer "F.SilkS")
			(hide yes)
			(effects
				(font
					(size 1.27 1.27)
				)
			)
		)
		(property "Value" "0R2J-2-GP"
			(at 0.064008 -3.993896 180)
			(unlocked yes)
			(layer "F.Fab")
			(hide yes)
			(effects
				(font
					(size 1.016 1.016)
					(thickness 0.1524)
				)
			)
		)
		(property "Device Type" "R402H16"
			(at 0.064008 -5.517896 180)
			(unlocked yes)
			(layer "F.Fab")
			(hide yes)
			(effects
				(font
					(size 1.016 1.016)
					(thickness 0.1524)
				)
			)
		)
		(duplicate_pad_numbers_are_jumpers no)
		(fp_line
			(start 0.508 -0.9398)
			(end -0.508 -0.9398)
			(stroke
				(width 0.1524)
				(type default)
			)
			(layer "F.SilkS")
		)
		(fp_line
			(start -0.508 -0.9398)
			(end -0.508 0.9398)
			(stroke
				(width 0.1524)
				(type default)
			)
			(layer "F.SilkS")
		)
		(fp_rect
			(start -0.508 0.9398)
			(end 0.508 -0.9398)
			(stroke
				(width 0)
				(type default)
			)
			(fill no)
			(layer "F.CrtYd")
		)
		(fp_rect
			(start -0.508 0.9398)
			(end 0.508 -0.9398)
			(stroke
				(width 0)
				(type default)
			)
			(fill no)
			(layer "F.Fab")
		)
		(pad "1" smd custom
			(at 0 -0.4445 180)
			(size 0.1397 0.1397)
			(layers "F.Cu" "F.Mask" "F.Paste")
			(net "SAS_SDBTX_R")
			(options
				(clearance outline)
				(anchor circle)
			)
			(primitives
				(gr_poly
					(pts
						(arc
							(start -0.1778 -0.2794)
							(mid -0.249642 -0.249642)
							(end -0.2794 -0.1778)
						)
						(arc
							(start -0.2794 0.1778)
							(mid -0.249642 0.249642)
							(end -0.1778 0.2794)
						)
						(arc
							(start 0.1778 0.2794)
							(mid 0.249642 0.249642)
							(end 0.2794 0.1778)
						)
						(arc
							(start 0.2794 -0.1778)
							(mid 0.249642 -0.249642)
							(end 0.1778 -0.2794)
						)
					)
					(width 0)
					(fill yes)
				)
			)
		)
		(pad "2" smd custom
			(at 0 0.4445 180)
			(size 0.1397 0.1397)
			(layers "F.Cu" "F.Mask" "F.Paste")
			(net "SAS_SDBTX")
			(options
				(clearance outline)
				(anchor circle)
			)
			(primitives
				(gr_poly
					(pts
						(arc
							(start -0.1778 -0.2794)
							(mid -0.249642 -0.249642)
							(end -0.2794 -0.1778)
						)
						(arc
							(start -0.2794 0.1778)
							(mid -0.249642 0.249642)
							(end -0.1778 0.2794)
						)
						(arc
							(start 0.1778 0.2794)
							(mid 0.249642 0.249642)
							(end 0.2794 0.1778)
						)
						(arc
							(start 0.2794 -0.1778)
							(mid 0.249642 -0.249642)
							(end 0.1778 -0.2794)
						)
					)
					(width 0)
					(fill yes)
				)
			)
		)
	)
	(footprint ""
		(layer "F.Cu")
		(at 348.390718 -153.012648 -90)
		(property "Reference" "R451"
			(at 0 0 270)
			(layer "F.SilkS")
			(hide yes)
			(effects
				(font
					(size 1.27 1.27)
				)
			)
		)
		(property "Value" "0R2J-2-GP"
			(at 0.064008 -3.993896 270)
			(unlocked yes)
			(layer "F.Fab")
			(hide yes)
			(effects
				(font
					(size 1.016 1.016)
					(thickness 0.1524)
				)
			)
		)
		(property "Device Type" "R402H16"
			(at 0.064008 -5.517896 270)
			(unlocked yes)
			(layer "F.Fab")
			(hide yes)
			(effects
				(font
					(size 1.016 1.016)
					(thickness 0.1524)
				)
			)
		)
		(duplicate_pad_numbers_are_jumpers no)
		(fp_line
			(start -0.508 -0.9398)
			(end -0.508 0.9398)
			(stroke
				(width 0.1524)
				(type default)
			)
			(layer "F.SilkS")
		)
		(fp_line
			(start 0.508 -0.9398)
			(end -0.508 -0.9398)
			(stroke
				(width 0.1524)
				(type default)
			)
			(layer "F.SilkS")
		)
		(fp_rect
			(start -0.508 0.9398)
			(end 0.508 -0.9398)
			(stroke
				(width 0)
				(type default)
			)
			(fill no)
			(layer "F.CrtYd")
		)
		(fp_rect
			(start -0.508 0.9398)
			(end 0.508 -0.9398)
			(stroke
				(width 0)
				(type default)
			)
			(fill no)
			(layer "F.Fab")
		)
		(pad "1" smd custom
			(at 0 -0.4445 270)
			(size 0.1397 0.1397)
			(layers "F.Cu" "F.Mask" "F.Paste")
			(net "BMC_USB1_HDP")
			(options
				(clearance outline)
				(anchor circle)
			)
			(primitives
				(gr_poly
					(pts
						(arc
							(start -0.1778 -0.2794)
							(mid -0.249642 -0.249642)
							(end -0.2794 -0.1778)
						)
						(arc
							(start -0.2794 0.1778)
							(mid -0.249642 0.249642)
							(end -0.1778 0.2794)
						)
						(arc
							(start 0.1778 0.2794)
							(mid 0.249642 0.249642)
							(end 0.2794 0.1778)
						)
						(arc
							(start 0.2794 -0.1778)
							(mid 0.249642 -0.249642)
							(end 0.1778 -0.2794)
						)
					)
					(width 0)
					(fill yes)
				)
			)
		)
		(pad "2" smd custom
			(at 0 0.4445 270)
			(size 0.1397 0.1397)
			(layers "F.Cu" "F.Mask" "F.Paste")
			(net "USB_P3_DP")
			(options
				(clearance outline)
				(anchor circle)
			)
			(primitives
				(gr_poly
					(pts
						(arc
							(start -0.1778 -0.2794)
							(mid -0.249642 -0.249642)
							(end -0.2794 -0.1778)
						)
						(arc
							(start -0.2794 0.1778)
							(mid -0.249642 0.249642)
							(end -0.1778 0.2794)
						)
						(arc
							(start 0.1778 0.2794)
							(mid 0.249642 0.249642)
							(end 0.2794 0.1778)
						)
						(arc
							(start 0.2794 -0.1778)
							(mid 0.249642 -0.249642)
							(end 0.1778 -0.2794)
						)
					)
					(width 0)
					(fill yes)
				)
			)
		)
	)
	(footprint ""
		(layer "F.Cu")
		(at 136.779 -40.64)
		(property "Reference" "STP116"
			(at 0 0 0)
			(layer "F.SilkS")
			(hide yes)
			(effects
				(font
					(size 1.27 1.27)
				)
			)
		)
		(property "Value" "TPAD28"
			(at 0.0127 -1.8034 0)
			(unlocked yes)
			(layer "F.Fab")
			(hide yes)
			(effects
				(font
					(size 1.016 1.016)
					(thickness 0.1524)
				)
			)
		)
		(property "Device Type" "TPAD28"
			(at 0.0127 -3.3274 0)
			(unlocked yes)
			(layer "F.Fab")
			(hide yes)
			(effects
				(font
					(size 1.016 1.016)
					(thickness 0.1524)
				)
			)
		)
		(duplicate_pad_numbers_are_jumpers no)
		(fp_poly
			(pts
				(arc
					(start 0.3556 0)
					(mid -0.3556 0)
					(end 0.3556 0)
				)
			)
			(stroke
				(width 0)
				(type default)
			)
			(fill no)
			(layer "F.CrtYd")
		)
		(fp_poly
			(pts
				(arc
					(start 0.6096 0)
					(mid -0.6096 0)
					(end 0.6096 0)
				)
			)
			(stroke
				(width 0)
				(type default)
			)
			(fill no)
			(layer "F.Fab")
		)
		(pad "1" smd circle
			(at 0 0)
			(size 0.7112 0.7112)
			(layers "F.Cu" "F.Mask" "F.Paste")
			(net "XM_ADDR_16")
		)
	)
	(footprint ""
		(layer "F.Cu")
		(at 81.915 -23.749 -90)
		(property "Reference" "PR190"
			(at 0 0 270)
			(layer "F.SilkS")
			(hide yes)
			(effects
				(font
					(size 1.27 1.27)
				)
			)
		)
		(property "Value" "7K32R2F-GP"
			(at 0.064008 -3.993896 270)
			(unlocked yes)
			(layer "F.Fab")
			(hide yes)
			(effects
				(font
					(size 1.016 1.016)
					(thickness 0.1524)
				)
			)
		)
		(property "Device Type" "R402H16"
			(at 0.064008 -5.517896 270)
			(unlocked yes)
			(layer "F.Fab")
			(hide yes)
			(effects
				(font
					(size 1.016 1.016)
					(thickness 0.1524)
				)
			)
		)
		(duplicate_pad_numbers_are_jumpers no)
		(fp_line
			(start -0.508 -0.9398)
			(end -0.508 0.9398)
			(stroke
				(width 0.1524)
				(type default)
			)
			(layer "F.SilkS")
		)
		(fp_line
			(start 0.508 -0.9398)
			(end -0.508 -0.9398)
			(stroke
				(width 0.1524)
				(type default)
			)
			(layer "F.SilkS")
		)
		(fp_rect
			(start -0.508 0.9398)
			(end 0.508 -0.9398)
			(stroke
				(width 0)
				(type default)
			)
			(fill no)
			(layer "F.CrtYd")
		)
		(fp_rect
			(start -0.508 0.9398)
			(end 0.508 -0.9398)
			(stroke
				(width 0)
				(type default)
			)
			(fill no)
			(layer "F.Fab")
		)
		(pad "1" smd custom
			(at 0 -0.4445 270)
			(size 0.1397 0.1397)
			(layers "F.Cu" "F.Mask" "F.Paste")
			(net "VT235_VREF")
			(options
				(clearance outline)
				(anchor circle)
			)
			(primitives
				(gr_poly
					(pts
						(arc
							(start -0.1778 -0.2794)
							(mid -0.249642 -0.249642)
							(end -0.2794 -0.1778)
						)
						(arc
							(start -0.2794 0.1778)
							(mid -0.249642 0.249642)
							(end -0.1778 0.2794)
						)
						(arc
							(start 0.1778 0.2794)
							(mid 0.249642 0.249642)
							(end 0.2794 0.1778)
						)
						(arc
							(start 0.2794 -0.1778)
							(mid 0.249642 -0.249642)
							(end 0.1778 -0.2794)
						)
					)
					(width 0)
					(fill yes)
				)
			)
		)
		(pad "2" smd custom
			(at 0 0.4445 270)
			(size 0.1397 0.1397)
			(layers "F.Cu" "F.Mask" "F.Paste")
			(net "VT235_VDES_RR")
			(options
				(clearance outline)
				(anchor circle)
			)
			(primitives
				(gr_poly
					(pts
						(arc
							(start -0.1778 -0.2794)
							(mid -0.249642 -0.249642)
							(end -0.2794 -0.1778)
						)
						(arc
							(start -0.2794 0.1778)
							(mid -0.249642 0.249642)
							(end -0.1778 0.2794)
						)
						(arc
							(start 0.1778 0.2794)
							(mid 0.249642 0.249642)
							(end 0.2794 0.1778)
						)
						(arc
							(start 0.2794 -0.1778)
							(mid 0.249642 -0.249642)
							(end 0.1778 -0.2794)
						)
					)
					(width 0)
					(fill yes)
				)
			)
		)
	)
	(footprint ""
		(layer "F.Cu")
		(at 323.342 -182.372)
		(property "Reference" "C8085"
			(at 0 0 0)
			(layer "F.SilkS")
			(hide yes)
			(effects
				(font
					(size 1.27 1.27)
				)
			)
		)
		(property "Value" "SCD1U25V2KX-2-GP"
			(at 1.1811 -2.7051 0)
			(unlocked yes)
			(layer "F.Fab")
			(hide yes)
			(effects
				(font
					(size 1.016 1.016)
					(thickness 0.1524)
				)
			)
		)
		(property "Device Type" "C402H22"
			(at 1.1811 -4.2291 0)
			(unlocked yes)
			(layer "F.Fab")
			(hide yes)
			(effects
				(font
					(size 1.016 1.016)
					(thickness 0.1524)
				)
			)
		)
		(duplicate_pad_numbers_are_jumpers no)
		(fp_rect
			(start -0.4318 0.9525)
			(end 0.4318 -0.9525)
			(stroke
				(width 0)
				(type default)
			)
			(fill no)
			(layer "F.CrtYd")
		)
		(fp_rect
			(start -0.4318 0.9525)
			(end 0.4318 -0.9525)
			(stroke
				(width 0)
				(type default)
			)
			(fill no)
			(layer "F.Fab")
		)
		(pad "1" smd custom
			(at 0 -0.4445)
			(size 0.1524 0.1524)
			(layers "F.Cu" "F.Mask" "F.Paste")
			(net "ADC_P1V8_STBY")
			(options
				(clearance outline)
				(anchor circle)
			)
			(primitives
				(gr_poly
					(pts
						(arc
							(start 0.3048 -0.2032)
							(mid 0.275042 -0.275042)
							(end 0.2032 -0.3048)
						)
						(arc
							(start -0.2032 -0.3048)
							(mid -0.275042 -0.275042)
							(end -0.3048 -0.2032)
						)
						(arc
							(start -0.3048 0.2032)
							(mid -0.275042 0.275042)
							(end -0.2032 0.3048)
						)
						(arc
							(start 0.2032 0.3048)
							(mid 0.275042 0.275042)
							(end 0.3048 0.2032)
						)
					)
					(width 0)
					(fill yes)
				)
			)
		)
		(pad "2" smd custom
			(at 0 0.4445)
			(size 0.1524 0.1524)
			(layers "F.Cu" "F.Mask" "F.Paste")
			(net "GND")
			(options
				(clearance outline)
				(anchor circle)
			)
			(primitives
				(gr_poly
					(pts
						(arc
							(start 0.3048 -0.2032)
							(mid 0.275042 -0.275042)
							(end 0.2032 -0.3048)
						)
						(arc
							(start -0.2032 -0.3048)
							(mid -0.275042 -0.275042)
							(end -0.3048 -0.2032)
						)
						(arc
							(start -0.3048 0.2032)
							(mid -0.275042 0.275042)
							(end -0.2032 0.3048)
						)
						(arc
							(start 0.2032 0.3048)
							(mid 0.275042 0.275042)
							(end 0.3048 0.2032)
						)
					)
					(width 0)
					(fill yes)
				)
			)
		)
	)
	(footprint ""
		(layer "F.Cu")
		(at 338.700872 -171.395136 180)
		(property "Reference" "R278"
			(at 0 0 180)
			(layer "F.SilkS")
			(hide yes)
			(effects
				(font
					(size 1.27 1.27)
				)
			)
		)
		(property "Value" "0R2J-2-GP"
			(at 0.064008 -3.993896 180)
			(unlocked yes)
			(layer "F.Fab")
			(hide yes)
			(effects
				(font
					(size 1.016 1.016)
					(thickness 0.1524)
				)
			)
		)
		(property "Device Type" "R402H16"
			(at 0.064008 -5.517896 180)
			(unlocked yes)
			(layer "F.Fab")
			(hide yes)
			(effects
				(font
					(size 1.016 1.016)
					(thickness 0.1524)
				)
			)
		)
		(duplicate_pad_numbers_are_jumpers no)
		(fp_line
			(start 0.508 -0.9398)
			(end -0.508 -0.9398)
			(stroke
				(width 0.1524)
				(type default)
			)
			(layer "F.SilkS")
		)
		(fp_line
			(start -0.508 -0.9398)
			(end -0.508 0.9398)
			(stroke
				(width 0.1524)
				(type default)
			)
			(layer "F.SilkS")
		)
		(fp_rect
			(start -0.508 0.9398)
			(end 0.508 -0.9398)
			(stroke
				(width 0)
				(type default)
			)
			(fill no)
			(layer "F.CrtYd")
		)
		(fp_rect
			(start -0.508 0.9398)
			(end 0.508 -0.9398)
			(stroke
				(width 0)
				(type default)
			)
			(fill no)
			(layer "F.Fab")
		)
		(pad "1" smd custom
			(at 0 -0.4445 180)
			(size 0.1397 0.1397)
			(layers "F.Cu" "F.Mask" "F.Paste")
			(net "BMC_UART_SWITCH_R")
			(options
				(clearance outline)
				(anchor circle)
			)
			(primitives
				(gr_poly
					(pts
						(arc
							(start -0.1778 -0.2794)
							(mid -0.249642 -0.249642)
							(end -0.2794 -0.1778)
						)
						(arc
							(start -0.2794 0.1778)
							(mid -0.249642 0.249642)
							(end -0.1778 0.2794)
						)
						(arc
							(start 0.1778 0.2794)
							(mid 0.249642 0.249642)
							(end 0.2794 0.1778)
						)
						(arc
							(start 0.2794 -0.1778)
							(mid 0.249642 -0.249642)
							(end 0.1778 -0.2794)
						)
					)
					(width 0)
					(fill yes)
				)
			)
		)
		(pad "2" smd custom
			(at 0 0.4445 180)
			(size 0.1397 0.1397)
			(layers "F.Cu" "F.Mask" "F.Paste")
			(net "GND")
			(options
				(clearance outline)
				(anchor circle)
			)
			(primitives
				(gr_poly
					(pts
						(arc
							(start -0.1778 -0.2794)
							(mid -0.249642 -0.249642)
							(end -0.2794 -0.1778)
						)
						(arc
							(start -0.2794 0.1778)
							(mid -0.249642 0.249642)
							(end -0.1778 0.2794)
						)
						(arc
							(start 0.1778 0.2794)
							(mid 0.249642 0.249642)
							(end 0.2794 0.1778)
						)
						(arc
							(start 0.2794 -0.1778)
							(mid 0.249642 -0.249642)
							(end 0.1778 -0.2794)
						)
					)
					(width 0)
					(fill yes)
				)
			)
		)
	)
	(footprint ""
		(layer "F.Cu")
		(at 280.915872 -215.591136 180)
		(property "Reference" "PR83"
			(at 0 0 180)
			(layer "F.SilkS")
			(hide yes)
			(effects
				(font
					(size 1.27 1.27)
				)
			)
		)
		(property "Value" "0R2J-2-GP"
			(at 0.064008 -3.993896 180)
			(unlocked yes)
			(layer "F.Fab")
			(hide yes)
			(effects
				(font
					(size 1.016 1.016)
					(thickness 0.1524)
				)
			)
		)
		(property "Device Type" "R402H16"
			(at 0.064008 -5.517896 180)
			(unlocked yes)
			(layer "F.Fab")
			(hide yes)
			(effects
				(font
					(size 1.016 1.016)
					(thickness 0.1524)
				)
			)
		)
		(duplicate_pad_numbers_are_jumpers no)
		(fp_line
			(start 0.508 -0.9398)
			(end -0.508 -0.9398)
			(stroke
				(width 0.1524)
				(type default)
			)
			(layer "F.SilkS")
		)
		(fp_line
			(start -0.508 -0.9398)
			(end -0.508 0.9398)
			(stroke
				(width 0.1524)
				(type default)
			)
			(layer "F.SilkS")
		)
		(fp_rect
			(start -0.508 0.9398)
			(end 0.508 -0.9398)
			(stroke
				(width 0)
				(type default)
			)
			(fill no)
			(layer "F.CrtYd")
		)
		(fp_rect
			(start -0.508 0.9398)
			(end 0.508 -0.9398)
			(stroke
				(width 0)
				(type default)
			)
			(fill no)
			(layer "F.Fab")
		)
		(pad "1" smd custom
			(at 0 -0.4445 180)
			(size 0.1397 0.1397)
			(layers "F.Cu" "F.Mask" "F.Paste")
			(net "P1V8_STBY_PG")
			(options
				(clearance outline)
				(anchor circle)
			)
			(primitives
				(gr_poly
					(pts
						(arc
							(start -0.1778 -0.2794)
							(mid -0.249642 -0.249642)
							(end -0.2794 -0.1778)
						)
						(arc
							(start -0.2794 0.1778)
							(mid -0.249642 0.249642)
							(end -0.1778 0.2794)
						)
						(arc
							(start 0.1778 0.2794)
							(mid 0.249642 0.249642)
							(end 0.2794 0.1778)
						)
						(arc
							(start 0.2794 -0.1778)
							(mid 0.249642 -0.249642)
							(end 0.1778 -0.2794)
						)
					)
					(width 0)
					(fill yes)
				)
			)
		)
		(pad "2" smd custom
			(at 0 0.4445 180)
			(size 0.1397 0.1397)
			(layers "F.Cu" "F.Mask" "F.Paste")
			(net "TPS74801_1V53_STBY_EN")
			(options
				(clearance outline)
				(anchor circle)
			)
			(primitives
				(gr_poly
					(pts
						(arc
							(start -0.1778 -0.2794)
							(mid -0.249642 -0.249642)
							(end -0.2794 -0.1778)
						)
						(arc
							(start -0.2794 0.1778)
							(mid -0.249642 0.249642)
							(end -0.1778 0.2794)
						)
						(arc
							(start 0.1778 0.2794)
							(mid 0.249642 0.249642)
							(end 0.2794 0.1778)
						)
						(arc
							(start 0.2794 -0.1778)
							(mid 0.249642 -0.249642)
							(end 0.1778 -0.2794)
						)
					)
					(width 0)
					(fill yes)
				)
			)
		)
	)
)
